(kicad_pcb
	(version 20260206)
	(generator "pcbnew")
	(generator_version "10.0")
	(general
		(thickness 1.6)
		(legacy_teardrops no)
	)
	(paper "A4")
	(title_block
		(title "Bryce Canyon_SCC_16316-1_OCP.brd")
		(comment 1 "Bryce Canyon / footprints 1347-1354 of 1561")
	)
	(layers
		(0 "F.Cu" signal "TOP")
		(4 "In1.Cu" signal "L2GND")
		(6 "In2.Cu" signal "L3")
		(8 "In3.Cu" signal "L4VCC")
		(10 "In4.Cu" signal "L5VCC")
		(12 "In5.Cu" signal "L6")
		(14 "In6.Cu" signal "L7GND")
		(2 "B.Cu" signal "BOTTOM")
		(9 "F.Adhes" user "F.Adhesive")
		(11 "B.Adhes" user "B.Adhesive")
		(13 "F.Paste" user "Package Geometry/Pastemask Top")
		(15 "B.Paste" user "Package Geometry/Pastemask Bottom")
		(5 "F.SilkS" user "Ref Des/Silkscreen Top")
		(7 "B.SilkS" user "Ref Des/Silkscreen Bottom")
		(1 "F.Mask" user "Board Geometry/Soldermask Top")
		(3 "B.Mask" user "Board Geometry/Soldermask Bottom")
		(17 "Dwgs.User" user "User.Drawings")
		(19 "Cmts.User" user "User.Comments")
		(21 "Eco1.User" user "User.Eco1")
		(23 "Eco2.User" user "User.Eco2")
		(25 "Edge.Cuts" user "Board Geometry/Outline")
		(27 "Margin" user)
		(31 "F.CrtYd" user "Package Geometry/Place Bound Top")
		(29 "B.CrtYd" user "Package Geometry/Place Bound Bottom")
		(35 "F.Fab" user "Ref Des/Assembly Top")
		(33 "B.Fab" user "Ref Des/Assembly Bottom")
	)
	(footprint ""
		(layer "B.Cu")
		(at 38.521132 -106.24058 90)
		(property "Reference" "C594"
			(at 0 0 90)
			(layer "B.SilkS")
			(hide yes)
			(effects
				(font
					(size 1.27 1.27)
				)
				(justify mirror)
			)
		)
		(property "Value" "SCD1U16V2KX-3GP"
			(at -1.1811 -2.7051 90)
			(unlocked yes)
			(layer "B.Fab")
			(hide yes)
			(effects
				(font
					(size 1.016 1.016)
					(thickness 0.1524)
				)
				(justify mirror)
			)
		)
		(property "Device Type" "C402H22"
			(at -1.1811 -4.2291 90)
			(unlocked yes)
			(layer "B.Fab")
			(hide yes)
			(effects
				(font
					(size 1.016 1.016)
					(thickness 0.1524)
				)
				(justify mirror)
			)
		)
		(duplicate_pad_numbers_are_jumpers no)
		(fp_rect
			(start 0.4318 0.9525)
			(end -0.4318 -0.9525)
			(stroke
				(width 0)
				(type default)
			)
			(fill no)
			(layer "B.CrtYd")
		)
		(fp_rect
			(start 0.4318 0.9525)
			(end -0.4318 -0.9525)
			(stroke
				(width 0)
				(type default)
			)
			(fill no)
			(layer "B.Fab")
		)
		(pad "1" smd custom
			(at 0 -0.4445 270)
			(size 0.1524 0.1524)
			(layers "B.Cu" "B.Mask" "B.Paste")
			(net "P5V")
			(options
				(clearance outline)
				(anchor circle)
			)
			(primitives
				(gr_poly
					(pts
						(arc
							(start 0.3048 0.2032)
							(mid 0.275042 0.275042)
							(end 0.2032 0.3048)
						)
						(arc
							(start -0.2032 0.3048)
							(mid -0.275042 0.275042)
							(end -0.3048 0.2032)
						)
						(arc
							(start -0.3048 -0.2032)
							(mid -0.275042 -0.275042)
							(end -0.2032 -0.3048)
						)
						(arc
							(start 0.2032 -0.3048)
							(mid 0.275042 -0.275042)
							(end 0.3048 -0.2032)
						)
					)
					(width 0)
					(fill yes)
				)
			)
		)
		(pad "2" smd custom
			(at 0 0.4445 270)
			(size 0.1524 0.1524)
			(layers "B.Cu" "B.Mask" "B.Paste")
			(net "GND")
			(options
				(clearance outline)
				(anchor circle)
			)
			(primitives
				(gr_poly
					(pts
						(arc
							(start 0.3048 0.2032)
							(mid 0.275042 0.275042)
							(end 0.2032 0.3048)
						)
						(arc
							(start -0.2032 0.3048)
							(mid -0.275042 0.275042)
							(end -0.3048 0.2032)
						)
						(arc
							(start -0.3048 -0.2032)
							(mid -0.275042 -0.275042)
							(end -0.2032 -0.3048)
						)
						(arc
							(start 0.2032 -0.3048)
							(mid 0.275042 -0.275042)
							(end 0.3048 -0.2032)
						)
					)
					(width 0)
					(fill yes)
				)
			)
		)
	)
	(footprint ""
		(layer "B.Cu")
		(at 91.018868 -71.192898 180)
		(property "Reference" "R152"
			(at 0 0 0)
			(layer "B.SilkS")
			(hide yes)
			(effects
				(font
					(size 1.27 1.27)
				)
				(justify mirror)
			)
		)
		(property "Value" "10R2F-L-GP"
			(at -0.064008 -3.993896 180)
			(unlocked yes)
			(layer "B.Fab")
			(hide yes)
			(effects
				(font
					(size 1.016 1.016)
					(thickness 0.1524)
				)
				(justify mirror)
			)
		)
		(property "Device Type" "R402H14"
			(at -0.064008 -5.517896 180)
			(unlocked yes)
			(layer "B.Fab")
			(hide yes)
			(effects
				(font
					(size 1.016 1.016)
					(thickness 0.1524)
				)
				(justify mirror)
			)
		)
		(duplicate_pad_numbers_are_jumpers no)
		(fp_line
			(start 0.508 -0.9398)
			(end 0.508 0.9398)
			(stroke
				(width 0.1524)
				(type default)
			)
			(layer "B.SilkS")
		)
		(fp_line
			(start -0.508 -0.9398)
			(end 0.508 -0.9398)
			(stroke
				(width 0.1524)
				(type default)
			)
			(layer "B.SilkS")
		)
		(fp_rect
			(start 0.508 0.9398)
			(end -0.508 -0.9398)
			(stroke
				(width 0)
				(type default)
			)
			(fill no)
			(layer "B.CrtYd")
		)
		(fp_rect
			(start 0.508 0.9398)
			(end -0.508 -0.9398)
			(stroke
				(width 0)
				(type default)
			)
			(fill no)
			(layer "B.Fab")
		)
		(pad "1" smd custom
			(at 0 -0.4445)
			(size 0.1397 0.1397)
			(layers "B.Cu" "B.Mask" "B.Paste")
			(net "P1V8_E")
			(options
				(clearance outline)
				(anchor circle)
			)
			(primitives
				(gr_poly
					(pts
						(arc
							(start -0.1778 0.2794)
							(mid -0.249642 0.249642)
							(end -0.2794 0.1778)
						)
						(arc
							(start -0.2794 -0.1778)
							(mid -0.249642 -0.249642)
							(end -0.1778 -0.2794)
						)
						(arc
							(start 0.1778 -0.2794)
							(mid 0.249642 -0.249642)
							(end 0.2794 -0.1778)
						)
						(arc
							(start 0.2794 0.1778)
							(mid 0.249642 0.249642)
							(end 0.1778 0.2794)
						)
					)
					(width 0)
					(fill yes)
				)
			)
		)
		(pad "2" smd custom
			(at 0 0.4445)
			(size 0.1397 0.1397)
			(layers "B.Cu" "B.Mask" "B.Paste")
			(net "SYSPLL_VDDA18")
			(options
				(clearance outline)
				(anchor circle)
			)
			(primitives
				(gr_poly
					(pts
						(arc
							(start -0.1778 0.2794)
							(mid -0.249642 0.249642)
							(end -0.2794 0.1778)
						)
						(arc
							(start -0.2794 -0.1778)
							(mid -0.249642 -0.249642)
							(end -0.1778 -0.2794)
						)
						(arc
							(start 0.1778 -0.2794)
							(mid 0.249642 -0.249642)
							(end 0.2794 -0.1778)
						)
						(arc
							(start 0.2794 0.1778)
							(mid 0.249642 0.249642)
							(end 0.1778 0.2794)
						)
					)
					(width 0)
					(fill yes)
				)
			)
		)
	)
	(footprint ""
		(layer "B.Cu")
		(at 173.7868 -41.30802 -90)
		(property "Reference" "C443"
			(at 0 0 90)
			(layer "B.SilkS")
			(hide yes)
			(effects
				(font
					(size 1.27 1.27)
				)
				(justify mirror)
			)
		)
		(property "Value" "SCD1U6D3V1KX-GP"
			(at 2.8321 -1.7399 270)
			(unlocked yes)
			(layer "B.Fab")
			(hide yes)
			(effects
				(font
					(size 1.016 1.016)
					(thickness 0.1524)
				)
				(justify mirror)
			)
		)
		(property "Device Type" "C0201H13"
			(at 2.8321 -3.2639 270)
			(unlocked yes)
			(layer "B.Fab")
			(hide yes)
			(effects
				(font
					(size 1.016 1.016)
					(thickness 0.1524)
				)
				(justify mirror)
			)
		)
		(duplicate_pad_numbers_are_jumpers no)
		(fp_rect
			(start 0.2794 0.6477)
			(end -0.2794 -0.6477)
			(stroke
				(width 0)
				(type default)
			)
			(fill no)
			(layer "B.CrtYd")
		)
		(fp_rect
			(start 0.2794 0.6477)
			(end -0.2794 -0.6477)
			(stroke
				(width 0)
				(type default)
			)
			(fill no)
			(layer "B.Fab")
		)
		(pad "1" smd custom
			(at 0 -0.2794 90)
			(size 0.0762 0.0762)
			(layers "B.Cu" "B.Mask" "B.Paste")
			(net "P0V975")
			(options
				(clearance outline)
				(anchor circle)
			)
			(primitives
				(gr_poly
					(pts
						(arc
							(start 0.1524 0.127)
							(mid 0.137521 0.162921)
							(end 0.1016 0.1778)
						)
						(arc
							(start -0.1016 0.1778)
							(mid -0.137521 0.162921)
							(end -0.1524 0.127)
						)
						(arc
							(start -0.1524 -0.127)
							(mid -0.137521 -0.162921)
							(end -0.1016 -0.1778)
						)
						(arc
							(start 0.1016 -0.1778)
							(mid 0.137521 -0.162921)
							(end 0.1524 -0.127)
						)
					)
					(width 0)
					(fill yes)
				)
			)
		)
		(pad "2" smd custom
			(at 0 0.2794 90)
			(size 0.0762 0.0762)
			(layers "B.Cu" "B.Mask" "B.Paste")
			(net "GND")
			(options
				(clearance outline)
				(anchor circle)
			)
			(primitives
				(gr_poly
					(pts
						(arc
							(start 0.1524 0.127)
							(mid 0.137521 0.162921)
							(end 0.1016 0.1778)
						)
						(arc
							(start -0.1016 0.1778)
							(mid -0.137521 0.162921)
							(end -0.1524 0.127)
						)
						(arc
							(start -0.1524 -0.127)
							(mid -0.137521 -0.162921)
							(end -0.1016 -0.1778)
						)
						(arc
							(start 0.1016 -0.1778)
							(mid 0.137521 -0.162921)
							(end 0.1524 -0.127)
						)
					)
					(width 0)
					(fill yes)
				)
			)
		)
	)
	(footprint ""
		(layer "B.Cu")
		(at 171.838874 -97.188782)
		(property "Reference" "C626"
			(at 0 0 0)
			(layer "B.SilkS")
			(hide yes)
			(effects
				(font
					(size 1.27 1.27)
				)
				(justify mirror)
			)
		)
		(property "Value" "SCD33U16V3KX-1GP"
			(at 0 -2.8194 0)
			(unlocked yes)
			(layer "B.Fab")
			(hide yes)
			(effects
				(font
					(size 1.016 1.016)
					(thickness 0.1524)
				)
				(justify mirror)
			)
		)
		(property "Device Type" "C603H36"
			(at 0 -4.3434 0)
			(unlocked yes)
			(layer "B.Fab")
			(hide yes)
			(effects
				(font
					(size 1.016 1.016)
					(thickness 0.1524)
				)
				(justify mirror)
			)
		)
		(duplicate_pad_numbers_are_jumpers no)
		(fp_line
			(start -0.508 0)
			(end 0.508 0)
			(stroke
				(width 0.2032)
				(type default)
			)
			(layer "B.SilkS")
		)
		(fp_rect
			(start 0.5842 1.3335)
			(end -0.5842 -1.3335)
			(stroke
				(width 0)
				(type default)
			)
			(fill no)
			(layer "B.CrtYd")
		)
		(fp_rect
			(start 0.5842 1.3335)
			(end -0.5842 -1.3335)
			(stroke
				(width 0)
				(type default)
			)
			(fill no)
			(layer "B.Fab")
		)
		(pad "1" smd custom
			(at 0 -0.762 180)
			(size 0.2159 0.2159)
			(layers "B.Cu" "B.Mask" "B.Paste")
			(net "AVSO_VREF")
			(options
				(clearance outline)
				(anchor circle)
			)
			(primitives
				(gr_poly
					(pts
						(arc
							(start -0.3302 0.4318)
							(mid -0.402042 0.402042)
							(end -0.4318 0.3302)
						)
						(arc
							(start -0.4318 -0.3302)
							(mid -0.402042 -0.402042)
							(end -0.3302 -0.4318)
						)
						(arc
							(start 0.3302 -0.4318)
							(mid 0.402042 -0.402042)
							(end 0.4318 -0.3302)
						)
						(arc
							(start 0.4318 0.3302)
							(mid 0.402042 0.402042)
							(end 0.3302 0.4318)
						)
					)
					(width 0)
					(fill yes)
				)
			)
		)
		(pad "2" smd custom
			(at 0 0.762 180)
			(size 0.2159 0.2159)
			(layers "B.Cu" "B.Mask" "B.Paste")
			(net "GND")
			(options
				(clearance outline)
				(anchor circle)
			)
			(primitives
				(gr_poly
					(pts
						(arc
							(start -0.3302 0.4318)
							(mid -0.402042 0.402042)
							(end -0.4318 0.3302)
						)
						(arc
							(start -0.4318 -0.3302)
							(mid -0.402042 -0.402042)
							(end -0.3302 -0.4318)
						)
						(arc
							(start 0.3302 -0.4318)
							(mid 0.402042 -0.402042)
							(end 0.4318 -0.3302)
						)
						(arc
							(start 0.4318 0.3302)
							(mid 0.402042 0.402042)
							(end 0.3302 0.4318)
						)
					)
					(width 0)
					(fill yes)
				)
			)
		)
	)
	(footprint ""
		(layer "B.Cu")
		(at 136.2202 -79.6036 -90)
		(property "Reference" "C4"
			(at 0 0 90)
			(layer "B.SilkS")
			(hide yes)
			(effects
				(font
					(size 1.27 1.27)
				)
				(justify mirror)
			)
		)
		(property "Value" "SCD01U16V1KX-GP"
			(at 2.8321 -1.7399 270)
			(unlocked yes)
			(layer "B.Fab")
			(hide yes)
			(effects
				(font
					(size 1.016 1.016)
					(thickness 0.1524)
				)
				(justify mirror)
			)
		)
		(property "Device Type" "C0201H13"
			(at 2.8321 -3.2639 270)
			(unlocked yes)
			(layer "B.Fab")
			(hide yes)
			(effects
				(font
					(size 1.016 1.016)
					(thickness 0.1524)
				)
				(justify mirror)
			)
		)
		(duplicate_pad_numbers_are_jumpers no)
		(fp_rect
			(start 0.2794 0.6477)
			(end -0.2794 -0.6477)
			(stroke
				(width 0)
				(type default)
			)
			(fill no)
			(layer "B.CrtYd")
		)
		(fp_rect
			(start 0.2794 0.6477)
			(end -0.2794 -0.6477)
			(stroke
				(width 0)
				(type default)
			)
			(fill no)
			(layer "B.Fab")
		)
		(pad "1" smd custom
			(at 0 -0.2794 90)
			(size 0.0762 0.0762)
			(layers "B.Cu" "B.Mask" "B.Paste")
			(net "PHY_CONN_TO_EXP_10_DN")
			(options
				(clearance outline)
				(anchor circle)
			)
			(primitives
				(gr_poly
					(pts
						(arc
							(start 0.1524 0.127)
							(mid 0.137521 0.162921)
							(end 0.1016 0.1778)
						)
						(arc
							(start -0.1016 0.1778)
							(mid -0.137521 0.162921)
							(end -0.1524 0.127)
						)
						(arc
							(start -0.1524 -0.127)
							(mid -0.137521 -0.162921)
							(end -0.1016 -0.1778)
						)
						(arc
							(start 0.1016 -0.1778)
							(mid 0.137521 -0.162921)
							(end 0.1524 -0.127)
						)
					)
					(width 0)
					(fill yes)
				)
			)
		)
		(pad "2" smd custom
			(at 0 0.2794 90)
			(size 0.0762 0.0762)
			(layers "B.Cu" "B.Mask" "B.Paste")
			(net "PHY_CONN_TO_EXP_C_10_DN")
			(options
				(clearance outline)
				(anchor circle)
			)
			(primitives
				(gr_poly
					(pts
						(arc
							(start 0.1524 0.127)
							(mid 0.137521 0.162921)
							(end 0.1016 0.1778)
						)
						(arc
							(start -0.1016 0.1778)
							(mid -0.137521 0.162921)
							(end -0.1524 0.127)
						)
						(arc
							(start -0.1524 -0.127)
							(mid -0.137521 -0.162921)
							(end -0.1016 -0.1778)
						)
						(arc
							(start 0.1016 -0.1778)
							(mid 0.137521 -0.162921)
							(end 0.1524 -0.127)
						)
					)
					(width 0)
					(fill yes)
				)
			)
		)
	)
	(footprint ""
		(layer "B.Cu")
		(at 125.984 -85.344)
		(property "Reference" "TP160"
			(at 0 0 0)
			(layer "B.SilkS")
			(hide yes)
			(effects
				(font
					(size 1.27 1.27)
				)
				(justify mirror)
			)
		)
		(property "Value" "TPAD28-2-GP"
			(at 0.0127 -1.6637 0)
			(unlocked yes)
			(layer "B.Fab")
			(hide yes)
			(effects
				(font
					(size 1.016 1.016)
					(thickness 0.1524)
				)
				(justify mirror)
			)
		)
		(property "Device Type" "TPAD28"
			(at 0.0127 -3.1877 0)
			(unlocked yes)
			(layer "B.Fab")
			(hide yes)
			(effects
				(font
					(size 1.016 1.016)
					(thickness 0.1524)
				)
				(justify mirror)
			)
		)
		(duplicate_pad_numbers_are_jumpers no)
		(fp_poly
			(pts
				(arc
					(start 0.3556 0)
					(mid -0.3556 0)
					(end 0.3556 0)
				)
			)
			(stroke
				(width 0)
				(type default)
			)
			(fill no)
			(layer "B.CrtYd")
		)
		(fp_poly
			(pts
				(arc
					(start 0.6096 0)
					(mid -0.6096 0)
					(end 0.6096 0)
				)
			)
			(stroke
				(width 0)
				(type default)
			)
			(fill no)
			(layer "B.Fab")
		)
		(pad "1" smd circle
			(at 0 0 180)
			(size 0.7112 0.7112)
			(layers "B.Cu" "B.Mask" "B.Paste")
			(net "ICE_TRST_N")
		)
	)
	(footprint ""
		(layer "B.Cu")
		(at 163.1442 -50.419)
		(property "Reference" "TP94"
			(at 0 0 0)
			(layer "B.SilkS")
			(hide yes)
			(effects
				(font
					(size 1.27 1.27)
				)
				(justify mirror)
			)
		)
		(property "Value" "TPAD28-2-GP"
			(at 0.0127 -1.6637 0)
			(unlocked yes)
			(layer "B.Fab")
			(hide yes)
			(effects
				(font
					(size 1.016 1.016)
					(thickness 0.1524)
				)
				(justify mirror)
			)
		)
		(property "Device Type" "TPAD28"
			(at 0.0127 -3.1877 0)
			(unlocked yes)
			(layer "B.Fab")
			(hide yes)
			(effects
				(font
					(size 1.016 1.016)
					(thickness 0.1524)
				)
				(justify mirror)
			)
		)
		(duplicate_pad_numbers_are_jumpers no)
		(fp_poly
			(pts
				(arc
					(start 0.3556 0)
					(mid -0.3556 0)
					(end 0.3556 0)
				)
			)
			(stroke
				(width 0)
				(type default)
			)
			(fill no)
			(layer "B.CrtYd")
		)
		(fp_poly
			(pts
				(arc
					(start 0.6096 0)
					(mid -0.6096 0)
					(end 0.6096 0)
				)
			)
			(stroke
				(width 0)
				(type default)
			)
			(fill no)
			(layer "B.Fab")
		)
		(pad "1" smd circle
			(at 0 0 180)
			(size 0.7112 0.7112)
			(layers "B.Cu" "B.Mask" "B.Paste")
			(net "SIO_LOAD_1")
		)
	)
	(footprint ""
		(layer "B.Cu")
		(at 135.405622 -56.379618 180)
		(property "Reference" "C25"
			(at 0 0 0)
			(layer "B.SilkS")
			(hide yes)
			(effects
				(font
					(size 1.27 1.27)
				)
				(justify mirror)
			)
		)
		(property "Value" "SCD01U16V1KX-GP"
			(at 2.8321 -1.7399 180)
			(unlocked yes)
			(layer "B.Fab")
			(hide yes)
			(effects
				(font
					(size 1.016 1.016)
					(thickness 0.1524)
				)
				(justify mirror)
			)
		)
		(property "Device Type" "C0201H13"
			(at 2.8321 -3.2639 180)
			(unlocked yes)
			(layer "B.Fab")
			(hide yes)
			(effects
				(font
					(size 1.016 1.016)
					(thickness 0.1524)
				)
				(justify mirror)
			)
		)
		(duplicate_pad_numbers_are_jumpers no)
		(fp_rect
			(start 0.2794 0.6477)
			(end -0.2794 -0.6477)
			(stroke
				(width 0)
				(type default)
			)
			(fill no)
			(layer "B.CrtYd")
		)
		(fp_rect
			(start 0.2794 0.6477)
			(end -0.2794 -0.6477)
			(stroke
				(width 0)
				(type default)
			)
			(fill no)
			(layer "B.Fab")
		)
		(pad "1" smd custom
			(at 0 -0.2794)
			(size 0.0762 0.0762)
			(layers "B.Cu" "B.Mask" "B.Paste")
			(net "PHY_DPB_TO_SCC_31_DP")
			(options
				(clearance outline)
				(anchor circle)
			)
			(primitives
				(gr_poly
					(pts
						(arc
							(start 0.1524 0.127)
							(mid 0.137521 0.162921)
							(end 0.1016 0.1778)
						)
						(arc
							(start -0.1016 0.1778)
							(mid -0.137521 0.162921)
							(end -0.1524 0.127)
						)
						(arc
							(start -0.1524 -0.127)
							(mid -0.137521 -0.162921)
							(end -0.1016 -0.1778)
						)
						(arc
							(start 0.1016 -0.1778)
							(mid 0.137521 -0.162921)
							(end 0.1524 -0.127)
						)
					)
					(width 0)
					(fill yes)
				)
			)
		)
		(pad "2" smd custom
			(at 0 0.2794)
			(size 0.0762 0.0762)
			(layers "B.Cu" "B.Mask" "B.Paste")
			(net "PHY_DPB_TO_SCC_C_31_DP")
			(options
				(clearance outline)
				(anchor circle)
			)
			(primitives
				(gr_poly
					(pts
						(arc
							(start 0.1524 0.127)
							(mid 0.137521 0.162921)
							(end 0.1016 0.1778)
						)
						(arc
							(start -0.1016 0.1778)
							(mid -0.137521 0.162921)
							(end -0.1524 0.127)
						)
						(arc
							(start -0.1524 -0.127)
							(mid -0.137521 -0.162921)
							(end -0.1016 -0.1778)
						)
						(arc
							(start 0.1016 -0.1778)
							(mid 0.137521 -0.162921)
							(end 0.1524 -0.127)
						)
					)
					(width 0)
					(fill yes)
				)
			)
		)
	)
)
